# S9S_MB_2U (Grand Teton) — schematic netlist excerpt (pin names and nets, part order shuffled) for the footprints in the layout excerpt that follows; sources: Cadence DE-HDL packaged netlist, KiCad conversion of 03242023_DA0F0TMBIJ0_F0T_Motherboard_J_brd_V01_OCP.brd

R4787  Q_RES  1M 1% EMPTY  pkg 0402LF  page 307 : A = PWRGD_DSW_PWROK_TRIGGER ; B = PWRGD_DSW_PWROK_R5
R3573  Q_RES  33.2 1% CHIP  pkg 0402LF  page 172 : A = SMB_INA230_4_3V3AUX_SDA_R ; B = SMB_INA230_4_3V3AUX_SDA_R1

(kicad_pcb
	(version 20260206)
	(generator "pcbnew")
	(generator_version "10.0")
	(general
		(thickness 1.6)
		(legacy_teardrops no)
	)
	(paper "A4")
	(title_block
		(title "03242023_DA0F0TMBIJ0_F0T_Motherboard_J_brd_V01_OCP.brd")
		(comment 1 "Grand Teton / footprints 1319-1320 of 6105")
	)
	(layers
		(0 "F.Cu" signal "TOP")
		(4 "In1.Cu" signal "GND")
		(6 "In2.Cu" signal "IN1")
		(8 "In3.Cu" signal "GND1")
		(10 "In4.Cu" signal "IN2")
		(12 "In5.Cu" signal "GND2")
		(14 "In6.Cu" signal "IN3")
		(16 "In7.Cu" signal "GND3")
		(18 "In8.Cu" signal "VCC")
		(20 "In9.Cu" signal "VCC1")
		(22 "In10.Cu" signal "GND4")
		(24 "In11.Cu" signal "IN4")
		(26 "In12.Cu" signal "GND5")
		(28 "In13.Cu" signal "IN5")
		(30 "In14.Cu" signal "GND6")
		(32 "In15.Cu" signal "IN6")
		(34 "In16.Cu" signal "GND7")
		(2 "B.Cu" signal "BOTTOM")
		(9 "F.Adhes" user "F.Adhesive")
		(11 "B.Adhes" user "B.Adhesive")
		(13 "F.Paste" user "Package Geometry/Pastemask Top")
		(15 "B.Paste" user "Package Geometry/Pastemask Bottom")
		(5 "F.SilkS" user "Ref Des/Silkscreen Top")
		(7 "B.SilkS" user "Ref Des/Silkscreen Bottom")
		(1 "F.Mask" user "Board Geometry/Soldermask Top")
		(3 "B.Mask" user "Board Geometry/Soldermask Bottom")
		(17 "Dwgs.User" user "User.Drawings")
		(19 "Cmts.User" user "User.Comments")
		(21 "Eco1.User" user "User.Eco1")
		(23 "Eco2.User" user "User.Eco2")
		(25 "Edge.Cuts" user "Board Geometry/Outline")
		(27 "Margin" user)
		(31 "F.CrtYd" user "Package Geometry/Place Bound Top")
		(29 "B.CrtYd" user "Package Geometry/Place Bound Bottom")
		(35 "F.Fab" user "Ref Des/Assembly Top")
		(33 "B.Fab" user "Ref Des/Assembly Bottom")
	)
	(footprint ""
		(layer "F.Cu")
		(at 303.9872 -25.8064 180)
		(property "Reference" "R4787"
			(at 0 0 180)
			(layer "F.SilkS")
			(hide yes)
			(effects
				(font
					(size 1.27 1.27)
				)
			)
		)
		(property "Value" ""
			(at 0 0 180)
			(layer "F.Fab")
			(effects
				(font
					(size 1.27 1.27)
				)
			)
		)
		(duplicate_pad_numbers_are_jumpers no)
		(fp_line
			(start 0.7874 0.4064)
			(end -0.7874 0.4064)
			(stroke
				(width 0.1524)
				(type default)
			)
			(layer "F.SilkS")
		)
		(fp_line
			(start 0.7874 -0.4064)
			(end 0.7874 0.4064)
			(stroke
				(width 0.1524)
				(type default)
			)
			(layer "F.SilkS")
		)
		(fp_line
			(start -0.7874 0.4064)
			(end -0.7874 -0.4064)
			(stroke
				(width 0.1524)
				(type default)
			)
			(layer "F.SilkS")
		)
		(fp_line
			(start -0.7874 -0.4064)
			(end 0.7874 -0.4064)
			(stroke
				(width 0.1524)
				(type default)
			)
			(layer "F.SilkS")
		)
		(fp_line
			(start 0.67945 0.3048)
			(end 0.120396 0.3048)
			(stroke
				(width 0.1)
				(type default)
			)
			(layer "F.Fab")
		)
		(fp_line
			(start 0.67945 -0.3048)
			(end 0.67945 0.3048)
			(stroke
				(width 0.1)
				(type default)
			)
			(layer "F.Fab")
		)
		(fp_line
			(start 0.12065 -0.2794)
			(end 0.12065 -0.3048)
			(stroke
				(width 0.1)
				(type default)
			)
			(layer "F.Fab")
		)
		(fp_line
			(start 0.12065 -0.3048)
			(end 0.67945 -0.3048)
			(stroke
				(width 0.1)
				(type default)
			)
			(layer "F.Fab")
		)
		(fp_line
			(start 0.120396 0.3048)
			(end 0.120396 0.2794)
			(stroke
				(width 0.1)
				(type default)
			)
			(layer "F.Fab")
		)
		(fp_line
			(start 0.120396 0.2794)
			(end -0.12065 0.2794)
			(stroke
				(width 0.1)
				(type default)
			)
			(layer "F.Fab")
		)
		(fp_line
			(start -0.12065 0.3048)
			(end -0.67945 0.3048)
			(stroke
				(width 0.1)
				(type default)
			)
			(layer "F.Fab")
		)
		(fp_line
			(start -0.12065 0.2794)
			(end -0.12065 0.3048)
			(stroke
				(width 0.1)
				(type default)
			)
			(layer "F.Fab")
		)
		(fp_line
			(start -0.12065 -0.2794)
			(end 0.12065 -0.2794)
			(stroke
				(width 0.1)
				(type default)
			)
			(layer "F.Fab")
		)
		(fp_line
			(start -0.12065 -0.305054)
			(end -0.12065 -0.2794)
			(stroke
				(width 0.1)
				(type default)
			)
			(layer "F.Fab")
		)
		(fp_line
			(start -0.67945 0.3048)
			(end -0.67945 -0.305054)
			(stroke
				(width 0.1)
				(type default)
			)
			(layer "F.Fab")
		)
		(fp_line
			(start -0.67945 -0.305054)
			(end -0.12065 -0.305054)
			(stroke
				(width 0.1)
				(type default)
			)
			(layer "F.Fab")
		)
		(pad "1" smd circle
			(at -0.40005 0 180)
			(size 0 0)
			(layers "F.Cu" "F.Mask" "F.Paste")
			(net "PWRGD_DSW_PWROK_TRIGGER")
		)
		(pad "2" smd circle
			(at 0.40005 0 180)
			(size 0 0)
			(layers "F.Cu" "F.Mask" "F.Paste")
			(net "PWRGD_DSW_PWROK_R5")
		)
	)
	(footprint ""
		(layer "F.Cu")
		(at 150.67788 -47.970948 90)
		(property "Reference" "R3573"
			(at 0 0 90)
			(layer "F.SilkS")
			(hide yes)
			(effects
				(font
					(size 1.27 1.27)
				)
			)
		)
		(property "Value" ""
			(at 0 0 90)
			(layer "F.Fab")
			(effects
				(font
					(size 1.27 1.27)
				)
			)
		)
		(duplicate_pad_numbers_are_jumpers no)
		(fp_line
			(start 0.7874 -0.4064)
			(end 0.7874 0.4064)
			(stroke
				(width 0.1524)
				(type default)
			)
			(layer "F.SilkS")
		)
		(fp_line
			(start -0.7874 -0.4064)
			(end 0.7874 -0.4064)
			(stroke
				(width 0.1524)
				(type default)
			)
			(layer "F.SilkS")
		)
		(fp_line
			(start 0.7874 0.4064)
			(end -0.7874 0.4064)
			(stroke
				(width 0.1524)
				(type default)
			)
			(layer "F.SilkS")
		)
		(fp_line
			(start -0.7874 0.4064)
			(end -0.7874 -0.4064)
			(stroke
				(width 0.1524)
				(type default)
			)
			(layer "F.SilkS")
		)
		(fp_line
			(start -0.12065 -0.305054)
			(end -0.12065 -0.2794)
			(stroke
				(width 0.1)
				(type default)
			)
			(layer "F.Fab")
		)
		(fp_line
			(start -0.67945 -0.305054)
			(end -0.12065 -0.305054)
			(stroke
				(width 0.1)
				(type default)
			)
			(layer "F.Fab")
		)
		(fp_line
			(start 0.67945 -0.3048)
			(end 0.67945 0.3048)
			(stroke
				(width 0.1)
				(type default)
			)
			(layer "F.Fab")
		)
		(fp_line
			(start 0.12065 -0.3048)
			(end 0.67945 -0.3048)
			(stroke
				(width 0.1)
				(type default)
			)
			(layer "F.Fab")
		)
		(fp_line
			(start 0.12065 -0.2794)
			(end 0.12065 -0.3048)
			(stroke
				(width 0.1)
				(type default)
			)
			(layer "F.Fab")
		)
		(fp_line
			(start -0.12065 -0.2794)
			(end 0.12065 -0.2794)
			(stroke
				(width 0.1)
				(type default)
			)
			(layer "F.Fab")
		)
		(fp_line
			(start 0.120396 0.2794)
			(end -0.12065 0.2794)
			(stroke
				(width 0.1)
				(type default)
			)
			(layer "F.Fab")
		)
		(fp_line
			(start -0.12065 0.2794)
			(end -0.12065 0.3048)
			(stroke
				(width 0.1)
				(type default)
			)
			(layer "F.Fab")
		)
		(fp_line
			(start 0.67945 0.3048)
			(end 0.120396 0.3048)
			(stroke
				(width 0.1)
				(type default)
			)
			(layer "F.Fab")
		)
		(fp_line
			(start 0.120396 0.3048)
			(end 0.120396 0.2794)
			(stroke
				(width 0.1)
				(type default)
			)
			(layer "F.Fab")
		)
		(fp_line
			(start -0.12065 0.3048)
			(end -0.67945 0.3048)
			(stroke
				(width 0.1)
				(type default)
			)
			(layer "F.Fab")
		)
		(fp_line
			(start -0.67945 0.3048)
			(end -0.67945 -0.305054)
			(stroke
				(width 0.1)
				(type default)
			)
			(layer "F.Fab")
		)
		(pad "1" smd circle
			(at -0.40005 0 90)
			(size 0 0)
			(layers "F.Cu" "F.Mask" "F.Paste")
			(net "SMB_INA230_4_3V3AUX_SDA_R")
		)
		(pad "2" smd circle
			(at 0.40005 0 90)
			(size 0 0)
			(layers "F.Cu" "F.Mask" "F.Paste")
			(net "SMB_INA230_4_3V3AUX_SDA_R1")
		)
	)
)
